# BASEBOARD_FAB2 (Tioga Pass) — schematic netlist excerpt (pin names and nets, part order shuffled) for the footprints in the layout excerpt that follows; sources: Cadence DE-HDL packaged netlist, KiCad conversion of Wiwynn_Tioga_Pass_MB.brd

R4C3  RES  1.00K 1% EMPTY  pkg 0402  page 205 : A = VSENSE_PVSA_CPU0_P ; B = VSENSE_PVSA_CPU0_N
R8F25  RES  475.0 1% CHIP  pkg 0402  page 101 : A = A_COMP_CKMNG ; B = GND
C5G15  CAP_A  47UF 4V 20% X5R  pkg 0603V  page 217 : A = PVDDQ_ABC ; B = GND

(kicad_pcb
	(version 20260206)
	(generator "pcbnew")
	(generator_version "10.0")
	(general
		(thickness 1.6)
		(legacy_teardrops no)
	)
	(paper "A4")
	(title_block
		(title "Wiwynn_Tioga_Pass_MB.brd")
		(comment 1 "Tioga Pass / footprints 837-839 of 4770")
	)
	(layers
		(0 "F.Cu" signal "TOP")
		(4 "In1.Cu" signal "L2GND")
		(6 "In2.Cu" signal "L3")
		(8 "In3.Cu" signal "L4GND")
		(10 "In4.Cu" signal "L5")
		(12 "In5.Cu" signal "L6GND")
		(14 "In6.Cu" signal "L7VCC")
		(16 "In7.Cu" signal "L8VCC")
		(18 "In8.Cu" signal "L9GND")
		(20 "In9.Cu" signal "L10")
		(22 "In10.Cu" signal "L11GND")
		(24 "In11.Cu" signal "L12")
		(26 "In12.Cu" signal "L13GND")
		(2 "B.Cu" signal "BOTTOM")
		(9 "F.Adhes" user "F.Adhesive")
		(11 "B.Adhes" user "B.Adhesive")
		(13 "F.Paste" user "Package Geometry/Pastemask Top")
		(15 "B.Paste" user "Package Geometry/Pastemask Bottom")
		(5 "F.SilkS" user "Ref Des/Silkscreen Top")
		(7 "B.SilkS" user "Ref Des/Silkscreen Bottom")
		(1 "F.Mask" user "Board Geometry/Soldermask Top")
		(3 "B.Mask" user "Board Geometry/Soldermask Bottom")
		(17 "Dwgs.User" user "User.Drawings")
		(19 "Cmts.User" user "User.Comments")
		(21 "Eco1.User" user "User.Eco1")
		(23 "Eco2.User" user "User.Eco2")
		(25 "Edge.Cuts" user "Board Geometry/Outline")
		(27 "Margin" user)
		(31 "F.CrtYd" user "Package Geometry/Place Bound Top")
		(29 "B.CrtYd" user "Package Geometry/Place Bound Bottom")
		(35 "F.Fab" user "Ref Des/Assembly Top")
		(33 "B.Fab" user "Ref Des/Assembly Bottom")
	)
	(footprint ""
		(layer "F.Cu")
		(at 483.38486 -28.14828 90)
		(property "Reference" "R8F25"
			(at 0 0 90)
			(layer "F.SilkS")
			(hide yes)
			(effects
				(font
					(size 1.27 1.27)
				)
			)
		)
		(property "Value" ""
			(at 0 0 90)
			(layer "F.Fab")
			(effects
				(font
					(size 1.27 1.27)
				)
			)
		)
		(duplicate_pad_numbers_are_jumpers no)
		(fp_poly
			(pts
				(xy -0.2794 -0.1016) (xy 0.2794 -0.1016) (xy 0.2794 0.9906) (xy -0.2794 0.9906)
			)
			(stroke
				(width 0)
				(type default)
			)
			(fill no)
			(layer "F.CrtYd")
		)
		(fp_line
			(start 0.2794 -0.1016)
			(end -0.2794 -0.1016)
			(stroke
				(width 0.1)
				(type default)
			)
			(layer "F.Fab")
		)
		(fp_line
			(start -0.2794 -0.1016)
			(end -0.2794 0.9906)
			(stroke
				(width 0.1)
				(type default)
			)
			(layer "F.Fab")
		)
		(fp_line
			(start 0.2794 0.9906)
			(end 0.2794 -0.1016)
			(stroke
				(width 0.1)
				(type default)
			)
			(layer "F.Fab")
		)
		(fp_line
			(start -0.2794 0.9906)
			(end 0.2794 0.9906)
			(stroke
				(width 0.1)
				(type default)
			)
			(layer "F.Fab")
		)
		(pad "1" smd rect
			(at 0 0 90)
			(size 0.508 0.508)
			(layers "F.Cu" "F.Mask" "F.Paste")
			(net "A_COMP_CKMNG")
		)
		(pad "2" smd rect
			(at 0 0.889 90)
			(size 0.508 0.508)
			(layers "F.Cu" "F.Mask" "F.Paste")
			(net "GND")
		)
		(zone
			(layer "F.Cu")
			(hatch none 0.5)
			(connect_pads
				(clearance 0)
			)
			(min_thickness 0.25)
			(keepout
				(tracks allowed)
				(vias not_allowed)
				(pads allowed)
				(copperpour not_allowed)
				(footprints allowed)
			)
			(placement
				(enabled no)
				(sheetname "")
			)
			(fill
				(thermal_gap 0.5)
				(thermal_bridge_width 0.5)
				(island_removal_mode 0)
			)
			(polygon
				(pts
					(xy 483.63886 -27.89428) (xy 483.63886 -28.40228) (xy 484.01986 -28.40228) (xy 484.01986 -27.89428)
				)
			)
		)
		(zone
			(layer "F.Cu")
			(hatch none 0.5)
			(connect_pads
				(clearance 0)
			)
			(min_thickness 0.25)
			(keepout
				(tracks not_allowed)
				(vias allowed)
				(pads allowed)
				(copperpour not_allowed)
				(footprints allowed)
			)
			(placement
				(enabled no)
				(sheetname "")
			)
			(fill
				(thermal_gap 0.5)
				(thermal_bridge_width 0.5)
				(island_removal_mode 0)
			)
			(polygon
				(pts
					(xy 484.01986 -27.89428) (xy 484.01986 -28.40228) (xy 483.63886 -28.40228) (xy 483.63886 -27.89428)
				)
			)
		)
	)
	(footprint ""
		(layer "F.Cu")
		(at 205.486 -102.616 180)
		(property "Reference" "R4C3"
			(at 0 0 180)
			(layer "F.SilkS")
			(hide yes)
			(effects
				(font
					(size 1.27 1.27)
				)
			)
		)
		(property "Value" ""
			(at 0 0 180)
			(layer "F.Fab")
			(effects
				(font
					(size 1.27 1.27)
				)
			)
		)
		(duplicate_pad_numbers_are_jumpers no)
		(fp_poly
			(pts
				(xy -0.2794 -0.1016) (xy 0.2794 -0.1016) (xy 0.2794 0.9906) (xy -0.2794 0.9906)
			)
			(stroke
				(width 0)
				(type default)
			)
			(fill no)
			(layer "F.CrtYd")
		)
		(fp_line
			(start 0.2794 0.9906)
			(end 0.2794 -0.1016)
			(stroke
				(width 0.1)
				(type default)
			)
			(layer "F.Fab")
		)
		(fp_line
			(start 0.2794 -0.1016)
			(end -0.2794 -0.1016)
			(stroke
				(width 0.1)
				(type default)
			)
			(layer "F.Fab")
		)
		(fp_line
			(start -0.2794 0.9906)
			(end 0.2794 0.9906)
			(stroke
				(width 0.1)
				(type default)
			)
			(layer "F.Fab")
		)
		(fp_line
			(start -0.2794 -0.1016)
			(end -0.2794 0.9906)
			(stroke
				(width 0.1)
				(type default)
			)
			(layer "F.Fab")
		)
		(pad "1" smd rect
			(at 0 0 180)
			(size 0.508 0.508)
			(layers "F.Cu" "F.Mask" "F.Paste")
			(net "VSENSE_PVSA_CPU0_P")
		)
		(pad "2" smd rect
			(at 0 0.889 180)
			(size 0.508 0.508)
			(layers "F.Cu" "F.Mask" "F.Paste")
			(net "VSENSE_PVSA_CPU0_N")
		)
		(zone
			(layer "F.Cu")
			(hatch none 0.5)
			(connect_pads
				(clearance 0)
			)
			(min_thickness 0.25)
			(keepout
				(tracks not_allowed)
				(vias allowed)
				(pads allowed)
				(copperpour not_allowed)
				(footprints allowed)
			)
			(placement
				(enabled no)
				(sheetname "")
			)
			(fill
				(thermal_gap 0.5)
				(thermal_bridge_width 0.5)
				(island_removal_mode 0)
			)
			(polygon
				(pts
					(xy 205.74 -103.251) (xy 205.232 -103.251) (xy 205.232 -102.87) (xy 205.74 -102.87)
				)
			)
		)
		(zone
			(layer "F.Cu")
			(hatch none 0.5)
			(connect_pads
				(clearance 0)
			)
			(min_thickness 0.25)
			(keepout
				(tracks allowed)
				(vias not_allowed)
				(pads allowed)
				(copperpour not_allowed)
				(footprints allowed)
			)
			(placement
				(enabled no)
				(sheetname "")
			)
			(fill
				(thermal_gap 0.5)
				(thermal_bridge_width 0.5)
				(island_removal_mode 0)
			)
			(polygon
				(pts
					(xy 205.74 -102.87) (xy 205.232 -102.87) (xy 205.232 -103.251) (xy 205.74 -103.251)
				)
			)
		)
	)
	(footprint ""
		(layer "F.Cu")
		(at 266.397232 -3.3528 90)
		(property "Reference" "C5G15"
			(at 1.848866 0.752348 90)
			(unlocked yes)
			(layer "F.SilkS")
			(effects
				(font
					(size 1.27 0.9652)
					(thickness 0.1524)
				)
			)
		)
		(property "Value" ""
			(at 0 0 90)
			(layer "F.Fab")
			(effects
				(font
					(size 1.27 1.27)
				)
			)
		)
		(duplicate_pad_numbers_are_jumpers no)
		(fp_rect
			(start -0.500126 1.598422)
			(end 0.500126 -0.201422)
			(stroke
				(width 0)
				(type default)
			)
			(fill no)
			(layer "F.CrtYd")
		)
		(fp_line
			(start 0.500126 -0.201422)
			(end 0.500126 1.598422)
			(stroke
				(width 0.1)
				(type default)
			)
			(layer "F.Fab")
		)
		(fp_line
			(start -0.500126 -0.201422)
			(end 0.500126 -0.201422)
			(stroke
				(width 0.1)
				(type default)
			)
			(layer "F.Fab")
		)
		(fp_line
			(start 0.500126 1.598422)
			(end -0.500126 1.598422)
			(stroke
				(width 0.1)
				(type default)
			)
			(layer "F.Fab")
		)
		(fp_line
			(start -0.500126 1.598422)
			(end -0.500126 -0.201422)
			(stroke
				(width 0.1)
				(type default)
			)
			(layer "F.Fab")
		)
		(pad "1" smd rect
			(at 0 0)
			(size 0.889 0.9906)
			(layers "F.Cu" "F.Mask" "F.Paste")
			(net "PVDDQ_ABC")
		)
		(pad "2" smd rect
			(at 0 1.397)
			(size 0.889 0.9906)
			(layers "F.Cu" "F.Mask" "F.Paste")
			(net "GND")
		)
		(zone
			(layer "F.Cu")
			(hatch none 0.5)
			(connect_pads
				(clearance 0)
			)
			(min_thickness 0.25)
			(keepout
				(tracks not_allowed)
				(vias allowed)
				(pads allowed)
				(copperpour not_allowed)
				(footprints allowed)
			)
			(placement
				(enabled no)
				(sheetname "")
			)
			(fill
				(thermal_gap 0.5)
				(thermal_bridge_width 0.5)
				(island_removal_mode 0)
			)
			(polygon
				(pts
					(xy 267.349732 -2.8575) (xy 267.349732 -3.8481) (xy 266.841732 -3.8481) (xy 266.841732 -2.8575)
				)
			)
		)
		(zone
			(layer "F.Cu")
			(hatch none 0.5)
			(connect_pads
				(clearance 0)
			)
			(min_thickness 0.25)
			(keepout
				(tracks allowed)
				(vias not_allowed)
				(pads allowed)
				(copperpour not_allowed)
				(footprints allowed)
			)
			(placement
				(enabled no)
				(sheetname "")
			)
			(fill
				(thermal_gap 0.5)
				(thermal_bridge_width 0.5)
				(island_removal_mode 0)
			)
			(polygon
				(pts
					(xy 267.349732 -2.8575) (xy 267.349732 -3.8481) (xy 266.841732 -3.8481) (xy 266.841732 -2.8575)
				)
			)
		)
	)
)
